(kicad_pcb
	(version 20221018)
	(generator pcbnew)
	(general
    (thickness 1.6)
  )
	(paper "A4")
	(title_block
    (title "NUC Computer Cluster Power Breakout HW")
    (date "2023-10-18")
    (rev "1.4.3")
    (company "Antmicro Ltd.")
		(comment 9 "footprint 92 of 234 (J10), pads 1-44 of 44")
	)
	(layers
    (0 "F.Cu" mixed)
    (1 "In1.Cu" power)
    (2 "In2.Cu" mixed)
    (31 "B.Cu" power)
    (32 "B.Adhes" user "B.Adhesive")
    (33 "F.Adhes" user "F.Adhesive")
    (34 "B.Paste" user)
    (35 "F.Paste" user)
    (36 "B.SilkS" user "B.Silkscreen")
    (37 "F.SilkS" user "F.Silkscreen")
    (38 "B.Mask" user)
    (39 "F.Mask" user)
    (40 "Dwgs.User" user "User.Drawings")
    (41 "Cmts.User" user "User.Comments")
    (42 "Eco1.User" user "User.Eco1")
    (43 "Eco2.User" user "User.Eco2")
    (44 "Edge.Cuts" user)
    (45 "Margin" user)
    (46 "B.CrtYd" user "B.Courtyard")
    (47 "F.CrtYd" user "F.Courtyard")
    (48 "B.Fab" user)
    (49 "F.Fab" user)
  )
	(footprint "antmicro-footprints:Socket_Amphenol_HPCE_2x17_10107844-002LF"
    (layer "F.Cu")
    (at 140.009 150.519)
    (property "Author" "Antmicro")
    (property "License" "Apache-2.0")
    (property "MPN" "10107844-002LF")
    (property "Manufacturer" "Amphenol")
    (property "Sheetfile" "d1600e-psu-breakout-board.kicad_sch")
    (property "Sheetname" "")
    (property "ki_description" "60 (24 + 36 Power) Position Edge Card Connector")
    (property "ki_keywords" "HORIZONTAL, EDGE, CONNECTOR, SOCKET")
    (fp_text reference "J10" (at -37.159 -9.269) (layer "F.SilkS")
        (effects (font (size 0.7 0.7) (thickness 0.15)) (justify left bottom))
    )
    (fp_text value "Socket_Amphenol_HPCE_2x17_10107844-002LF" (at 0 13) (layer "F.Fab")
        (effects (font (size 0.7 0.7) (thickness 0.15)) (justify left bottom))
    )
    (pad "" np_thru_hole circle (at -35.329 -4.12) (size 3.7 3.7) (drill 3.7) (layers "F&B.Cu" "*.Mask"))
    (pad "" np_thru_hole circle (at 35.331 -4.12) (size 3.7 3.7) (drill 3.7) (layers "F&B.Cu" "*.Mask"))
    (pad "P1/2" smd rect (at 28.602 -9.6 90) (size 10 4.495) (layers "F.Cu")
      (net 11 "VCC12V0") (pinfunction "P1") (pintype "power_in"))
    (pad "P3/4" smd rect (at 23.637 -9.6 90) (size 10 4.495) (layers "F.Cu")
      (net 11 "VCC12V0") (pinfunction "P3") (pintype "power_in"))
    (pad "P5/6" smd rect (at 18.442 -9.6 90) (size 10 4.495) (layers "F.Cu")
      (net 11 "VCC12V0") (pinfunction "P5") (pintype "power_in"))
    (pad "P7/8" smd rect (at 13.478 -9.6 90) (size 10 4.495) (layers "F.Cu")
      (net 11 "VCC12V0") (pinfunction "P7") (pintype "power_in"))
    (pad "P9/10" smd rect (at 8.283 -9.6 90) (size 10 4.495) (layers "F.Cu")
      (net 4 "GND") (pinfunction "P9") (pintype "power_in"))
    (pad "P11/12" smd rect (at 3.317 -9.6 90) (size 10 4.495) (layers "F.Cu")
      (net 4 "GND") (pinfunction "P11") (pintype "power_in"))
    (pad "P13/14" smd rect (at -1.875 -9.6 90) (size 10 4.495) (layers "F.Cu")
      (net 4 "GND") (pinfunction "P13") (pintype "power_in"))
    (pad "P15/16" smd rect (at -6.841 -9.6 90) (size 10 4.495) (layers "F.Cu")
      (net 4 "GND") (pinfunction "P15") (pintype "power_in"))
    (pad "P17/18" smd rect (at -11.978 -9.6 90) (size 10 4.381) (layers "F.Cu")
      (net 4 "GND") (pinfunction "P17") (pintype "power_in"))
    (pad "P19/20" smd rect (at -11.978 -9.6 90) (size 10 4.381) (layers "B.Cu")
      (net 92 "unconnected-(J10-P19-PadP19{slash}20)") (pinfunction "P19") (pintype "power_in+no_connect"))
    (pad "P21/22" smd rect (at -6.841 -9.6 90) (size 10 4.495) (layers "B.Cu")
      (net 4 "GND") (pinfunction "P21") (pintype "power_in"))
    (pad "P23/24" smd rect (at -1.875 -9.6 90) (size 10 4.495) (layers "B.Cu")
      (net 4 "GND") (pinfunction "P23") (pintype "power_in"))
    (pad "P25/26" smd rect (at 3.317 -9.6 90) (size 10 4.495) (layers "B.Cu")
      (net 4 "GND") (pinfunction "P25") (pintype "power_in"))
    (pad "P27/28" smd rect (at 8.283 -9.6 90) (size 10 4.495) (layers "B.Cu")
      (net 4 "GND") (pinfunction "P27") (pintype "power_in"))
    (pad "P29/30" smd rect (at 13.478 -9.6 90) (size 10 4.495) (layers "B.Cu")
      (net 11 "VCC12V0") (pinfunction "P29") (pintype "power_in"))
    (pad "P31/32" smd rect (at 18.442 -9.6 90) (size 10 4.495) (layers "B.Cu")
      (net 11 "VCC12V0") (pinfunction "P31") (pintype "power_in"))
    (pad "P33/34" smd rect (at 23.637 -9.6 90) (size 10 4.495) (layers "B.Cu")
      (net 11 "VCC12V0") (pinfunction "P33") (pintype "power_in"))
    (pad "P35/36" smd rect (at 28.602 -9.6 90) (size 10 4.495) (layers "B.Cu")
      (net 11 "VCC12V0") (pinfunction "P35") (pintype "power_in"))
    (pad "S1" smd rect (at -16.758 -7.744) (size 0.81 6.3) (layers "F.Cu" "F.Paste" "F.Mask")
      (net 64 "Net-(J10-PadS1)") (pinfunction "S1") (pintype "passive"))
    (pad "S2" smd rect (at -18.029 -7.744) (size 0.81 6.3) (layers "F.Cu" "F.Paste" "F.Mask")
      (net 65 "Net-(J10-PadS2)") (pinfunction "S2") (pintype "passive"))
    (pad "S3" smd rect (at -19.298 -7.744) (size 0.81 6.3) (layers "F.Cu" "F.Paste" "F.Mask")
      (net 66 "Net-(J10-PadS3)") (pinfunction "S3") (pintype "passive"))
    (pad "S4" smd rect (at -20.569 -7.744) (size 0.81 6.3) (layers "F.Cu" "F.Paste" "F.Mask")
      (net 67 "Net-(J10-PadS4)") (pinfunction "S4") (pintype "passive"))
    (pad "S5" smd rect (at -21.839 -7.744) (size 0.81 6.3) (layers "F.Cu" "F.Paste" "F.Mask")
      (net 60 "Net-(J10-PadS5)") (pinfunction "S5") (pintype "passive"))
    (pad "S6" smd rect (at -23.109 -7.744) (size 0.81 6.3) (layers "F.Cu" "F.Paste" "F.Mask")
      (net 61 "Net-(J10-PadS6)") (pinfunction "S6") (pintype "passive"))
    (pad "S7" smd rect (at -24.379 -7.744) (size 0.81 6.3) (layers "F.Cu" "F.Paste" "F.Mask")
      (net 62 "Net-(J10-PadS7)") (pinfunction "S7") (pintype "passive"))
    (pad "S8" smd rect (at -25.649 -7.744) (size 0.81 6.3) (layers "F.Cu" "F.Paste" "F.Mask")
      (net 63 "Net-(J10-PadS8)") (pinfunction "S8") (pintype "passive"))
    (pad "S9" smd rect (at -26.919 -7.744) (size 0.81 6.3) (layers "F.Cu" "F.Paste" "F.Mask")
      (net 59 "Net-(J10-PadS9)") (pinfunction "S9") (pintype "passive"))
    (pad "S10" smd rect (at -28.189 -7.744) (size 0.81 6.3) (layers "F.Cu" "F.Paste" "F.Mask")
      (net 58 "Net-(J10-PadS10)") (pinfunction "S10") (pintype "passive"))
    (pad "S11" smd rect (at -29.458 -7.744) (size 0.81 6.3) (layers "F.Cu" "F.Paste" "F.Mask")
      (net 57 "Net-(J10-PadS11)") (pinfunction "S11") (pintype "passive"))
    (pad "S12" smd rect (at -30.729 -7.744) (size 0.81 6.3) (layers "F.Cu" "F.Paste" "F.Mask")
      (net 56 "Net-(J10-PadS12)") (pinfunction "S12") (pintype "passive"))
    (pad "S13" smd rect (at -30.729 -7.744) (size 0.81 6.3) (layers "B.Cu" "B.Paste" "B.Mask")
      (net 51 "PSU_ON") (pinfunction "S13") (pintype "passive"))
    (pad "S14" smd rect (at -29.458 -7.744) (size 0.81 6.3) (layers "B.Cu" "B.Paste" "B.Mask")
      (net 51 "PSU_ON") (pinfunction "S14") (pintype "passive"))
    (pad "S15" smd rect (at -28.189 -7.744) (size 0.81 6.3) (layers "B.Cu" "B.Paste" "B.Mask")
      (net 51 "PSU_ON") (pinfunction "S15") (pintype "passive"))
    (pad "S16" smd rect (at -26.919 -7.744) (size 0.81 6.3) (layers "B.Cu" "B.Paste" "B.Mask")
      (net 75 "Net-(J10-PadS16)") (pinfunction "S16") (pintype "passive"))
    (pad "S17" smd rect (at -25.649 -7.744) (size 0.81 6.3) (layers "B.Cu" "B.Paste" "B.Mask")
      (net 72 "Net-(J10-PadS17)") (pinfunction "S17") (pintype "passive"))
    (pad "S18" smd rect (at -24.379 -7.744) (size 0.81 6.3) (layers "B.Cu" "B.Paste" "B.Mask")
      (net 73 "Net-(J10-PadS18)") (pinfunction "S18") (pintype "passive"))
    (pad "S19" smd rect (at -23.109 -7.744) (size 0.81 6.3) (layers "B.Cu" "B.Paste" "B.Mask")
      (net 71 "Net-(J10-PadS19)") (pinfunction "S19") (pintype "passive"))
    (pad "S20" smd rect (at -21.839 -7.744) (size 0.81 6.3) (layers "B.Cu" "B.Paste" "B.Mask")
      (net 74 "Net-(J10-PadS20)") (pinfunction "S20") (pintype "passive"))
    (pad "S21" smd rect (at -20.569 -7.744) (size 0.81 6.3) (layers "B.Cu" "B.Paste" "B.Mask")
      (net 69 "Net-(J10-PadS21)") (pinfunction "S21") (pintype "passive"))
    (pad "S22" smd rect (at -19.298 -7.744) (size 0.81 6.3) (layers "B.Cu" "B.Paste" "B.Mask")
      (net 70 "Net-(J10-PadS22)") (pinfunction "S22") (pintype "passive"))
    (pad "S23" smd rect (at -18.029 -7.744) (size 0.81 6.3) (layers "B.Cu" "B.Paste" "B.Mask")
      (net 68 "Net-(J10-PadS23)") (pinfunction "S23") (pintype "passive"))
    (pad "S24" smd rect (at -16.758 -7.744) (size 0.81 6.3) (layers "B.Cu" "B.Paste" "B.Mask")
      (net 55 "Net-(J10-PadS24)") (pinfunction "S24") (pintype "passive"))
  )
)
